(kicad_pcb
	(version 20241229)
	(generator "pcbnew")
	(generator_version "9.0")
	(general
		(thickness 1.294)
		(legacy_teardrops no)
	)
	(paper "A3")
	(title_block
		(title "Kintex 410T devboard")
		(date "2024-04-03")
		(rev "1.1.2")
		(comment 9 "footprints 835-840 of 975")
	)
	(layers
		(0 "F.Cu" mixed)
		(4 "In1.Cu" power)
		(6 "In2.Cu" power)
		(8 "In3.Cu" mixed)
		(10 "In4.Cu" power)
		(12 "In5.Cu" mixed)
		(14 "In6.Cu" power)
		(16 "In7.Cu" mixed)
		(18 "In8.Cu" power)
		(2 "B.Cu" mixed)
		(9 "F.Adhes" user "F.Adhesive")
		(11 "B.Adhes" user "B.Adhesive")
		(13 "F.Paste" user)
		(15 "B.Paste" user)
		(5 "F.SilkS" user "F.Silkscreen")
		(7 "B.SilkS" user "B.Silkscreen")
		(1 "F.Mask" user)
		(3 "B.Mask" user)
		(17 "Dwgs.User" user "User.Drawings")
		(19 "Cmts.User" user "User.Comments")
		(21 "Eco1.User" user "User.Eco1")
		(23 "Eco2.User" user "User.Eco2")
		(25 "Edge.Cuts" user)
		(27 "Margin" user)
		(31 "F.CrtYd" user "F.Courtyard")
		(29 "B.CrtYd" user "B.Courtyard")
		(35 "F.Fab" user)
		(33 "B.Fab" user)
	)
	(footprint "antmicro-footprints:R_0402_1005Metric"
		(layer "B.Cu")
		(at 253.101 179.06 90)
		(descr "Resistor SMD 0402")
		(tags "resistor SMD 0402")
		(property "Reference" "R49"
			(at -0.775 0.374 270)
			(layer "B.SilkS")
			(effects
				(font
					(size 0.7 0.7)
					(thickness 0.15)
				)
				(justify left bottom mirror)
			)
		)
		(property "Value" "R_0R_0402"
			(at 0 -1.4 270)
			(layer "B.Fab")
			(effects
				(font
					(size 0.7 0.7)
					(thickness 0.15)
				)
				(justify left bottom mirror)
			)
		)
		(property "Description" "SMD Chip Resistor, Jumper, 0 ohm, 100 mW, 0402 [1005 Metric], Thick Film, General Purpose"
			(at 0 0 90)
			(layer "F.Fab")
			(hide yes)
			(effects
				(font
					(size 1.27 1.27)
					(thickness 0.15)
				)
			)
		)
		(property "Author" "Antmicro"
			(at 432.161 -74.041 0)
			(layer "B.Fab")
			(hide yes)
			(effects
				(font
					(size 1 1)
					(thickness 0.15)
				)
				(justify mirror)
			)
		)
		(property "Current" "1A"
			(at 432.161 -74.041 0)
			(layer "B.Fab")
			(hide yes)
			(effects
				(font
					(size 1 1)
					(thickness 0.15)
				)
				(justify mirror)
			)
		)
		(property "License" "Apache-2.0"
			(at 432.161 -74.041 0)
			(layer "B.Fab")
			(hide yes)
			(effects
				(font
					(size 1 1)
					(thickness 0.15)
				)
				(justify mirror)
			)
		)
		(property "MPN" "ERJ2GE0R00X"
			(at 432.161 -74.041 0)
			(layer "B.Fab")
			(hide yes)
			(effects
				(font
					(size 1 1)
					(thickness 0.15)
				)
				(justify mirror)
			)
		)
		(property "Manufacturer" "Panasonic"
			(at 432.161 -74.041 0)
			(layer "B.Fab")
			(hide yes)
			(effects
				(font
					(size 1 1)
					(thickness 0.15)
				)
				(justify mirror)
			)
		)
		(property "Tolerance" ""
			(at 432.161 -74.041 0)
			(layer "B.Fab")
			(hide yes)
			(effects
				(font
					(size 1 1)
					(thickness 0.15)
				)
				(justify mirror)
			)
		)
		(property "Val" "0R"
			(at 432.161 -74.041 0)
			(layer "B.Fab")
			(hide yes)
			(effects
				(font
					(size 1 1)
					(thickness 0.15)
				)
				(justify mirror)
			)
		)
		(sheetname "Power supply")
		(sheetfile "power-supply.kicad_sch")
		(attr smd)
		(fp_rect
			(start -0.925 0.47)
			(end 0.925 -0.47)
			(stroke
				(width 0.05)
				(type default)
			)
			(fill no)
			(layer "B.CrtYd")
		)
		(fp_rect
			(start -0.5 0.25)
			(end 0.5 -0.25)
			(stroke
				(width 0.15)
				(type solid)
			)
			(fill no)
			(layer "B.Fab")
		)
		(pad "1" smd roundrect
			(at -0.48 0 90)
			(size 0.59 0.64)
			(layers "B.Cu" "B.Mask" "B.Paste")
			(roundrect_rratio 0.25)
			(net 697 "/Power supply/VSS")
			(pintype "passive")
		)
		(pad "2" smd roundrect
			(at 0.48 0 90)
			(size 0.59 0.64)
			(layers "B.Cu" "B.Mask" "B.Paste")
			(roundrect_rratio 0.25)
			(net 883 "/Power supply/MPS_DUTY")
			(pintype "passive")
		)
	)
	(footprint "antmicro-footprints:C_0201"
		(layer "B.Cu")
		(at 193.125 132.75 90)
		(descr "Capacitor SMD 0201")
		(tags "capacitor SMD 0201")
		(property "Reference" "C110"
			(at 26.575 23.125 90)
			(layer "B.SilkS")
			(effects
				(font
					(size 0.7 0.7)
					(thickness 0.15)
				)
				(justify right bottom mirror)
			)
		)
		(property "Value" "C_4u7_0201"
			(at 0 -1.4 90)
			(layer "B.Fab")
			(effects
				(font
					(size 0.7 0.7)
					(thickness 0.15)
				)
				(justify right bottom mirror)
			)
		)
		(property "Description" "SMD Multilayer Ceramic Capacitor, 4.7 µF, 6.3 V, 0201 [0603 Metric], ± 20%, X5R, GRM Series"
			(at 0 0 90)
			(layer "F.Fab")
			(hide yes)
			(effects
				(font
					(size 1.27 1.27)
					(thickness 0.15)
				)
			)
		)
		(property "Author" "Antmicro"
			(at 325.875 -60.375 0)
			(layer "B.Fab")
			(hide yes)
			(effects
				(font
					(size 1 1)
					(thickness 0.15)
				)
				(justify mirror)
			)
		)
		(property "Dielectric" ""
			(at 325.875 -60.375 0)
			(layer "B.Fab")
			(hide yes)
			(effects
				(font
					(size 1 1)
					(thickness 0.15)
				)
				(justify mirror)
			)
		)
		(property "License" "Apache-2.0"
			(at 325.875 -60.375 0)
			(layer "B.Fab")
			(hide yes)
			(effects
				(font
					(size 1 1)
					(thickness 0.15)
				)
				(justify mirror)
			)
		)
		(property "MPN" "GRM035R60J475ME15D"
			(at 325.875 -60.375 0)
			(layer "B.Fab")
			(hide yes)
			(effects
				(font
					(size 1 1)
					(thickness 0.15)
				)
				(justify mirror)
			)
		)
		(property "Manufacturer" "Murata"
			(at 325.875 -60.375 0)
			(layer "B.Fab")
			(hide yes)
			(effects
				(font
					(size 1 1)
					(thickness 0.15)
				)
				(justify mirror)
			)
		)
		(property "Val" "4u7"
			(at 325.875 -60.375 0)
			(layer "B.Fab")
			(hide yes)
			(effects
				(font
					(size 1 1)
					(thickness 0.15)
				)
				(justify mirror)
			)
		)
		(property "Voltage" ""
			(at 325.875 -60.375 0)
			(layer "B.Fab")
			(hide yes)
			(effects
				(font
					(size 1 1)
					(thickness 0.15)
				)
				(justify mirror)
			)
		)
		(sheetname "FPGA supply")
		(sheetfile "fpga-supply.kicad_sch")
		(attr smd)
		(fp_rect
			(start -0.7 0.35)
			(end 0.7 -0.35)
			(stroke
				(width 0.05)
				(type default)
			)
			(fill no)
			(layer "B.CrtYd")
		)
		(fp_rect
			(start 0.3 -0.15)
			(end -0.301 0.149)
			(stroke
				(width 0.15)
				(type solid)
			)
			(fill no)
			(layer "B.Fab")
		)
		(pad "" smd roundrect
			(at -0.349 0.002 90)
			(size 0.318 0.36)
			(layers "B.Paste")
			(roundrect_rratio 0.25)
		)
		(pad "" smd roundrect
			(at 0.341 0.002 90)
			(size 0.318 0.36)
			(layers "B.Paste")
			(roundrect_rratio 0.25)
		)
		(pad "1" smd roundrect
			(at -0.321 0.002 90)
			(size 0.46 0.4)
			(layers "B.Cu" "B.Mask")
			(roundrect_rratio 0.25)
			(net 1 "GND")
			(pintype "passive")
		)
		(pad "2" smd roundrect
			(at 0.32 0.002 90)
			(size 0.46 0.4)
			(layers "B.Cu" "B.Mask")
			(roundrect_rratio 0.25)
			(net 26 "+1V8")
			(pintype "passive")
		)
	)
	(footprint "antmicro-footprints:C_0603_1608Metric"
		(layer "B.Cu")
		(at 207.65 130 180)
		(descr "Capacitor SMD 0603")
		(tags "capacitor 0603")
		(property "Reference" "C383"
			(at 0.4 -0.5 90)
			(layer "B.SilkS")
			(effects
				(font
					(size 0.7 0.7)
					(thickness 0.15)
				)
				(justify left bottom mirror)
			)
		)
		(property "Value" "C_47u_0603"
			(at 0 -1.6 0)
			(layer "B.Fab")
			(effects
				(font
					(size 0.7 0.7)
					(thickness 0.15)
				)
				(justify left bottom mirror)
			)
		)
		(property "Description" "SMD Multilayer Ceramic Capacitor, 47 µF, 6.3 V, 0603 [1608 Metric], ± 20%, X5R, GRM Series"
			(at 0 0 180)
			(layer "F.Fab")
			(hide yes)
			(effects
				(font
					(size 1.27 1.27)
					(thickness 0.15)
				)
			)
		)
		(property "Author" "Antmicro"
			(at 415.3 260 0)
			(layer "B.Fab")
			(hide yes)
			(effects
				(font
					(size 1 1)
					(thickness 0.15)
				)
				(justify mirror)
			)
		)
		(property "Dielectric" ""
			(at 415.3 260 0)
			(layer "B.Fab")
			(hide yes)
			(effects
				(font
					(size 1 1)
					(thickness 0.15)
				)
				(justify mirror)
			)
		)
		(property "License" "Apache-2.0"
			(at 415.3 260 0)
			(layer "B.Fab")
			(hide yes)
			(effects
				(font
					(size 1 1)
					(thickness 0.15)
				)
				(justify mirror)
			)
		)
		(property "MPN" "GRM188R60J476ME15D"
			(at 415.3 260 0)
			(layer "B.Fab")
			(hide yes)
			(effects
				(font
					(size 1 1)
					(thickness 0.15)
				)
				(justify mirror)
			)
		)
		(property "Manufacturer" "Murata"
			(at 415.3 260 0)
			(layer "B.Fab")
			(hide yes)
			(effects
				(font
					(size 1 1)
					(thickness 0.15)
				)
				(justify mirror)
			)
		)
		(property "Val" "47u"
			(at 415.3 260 0)
			(layer "B.Fab")
			(hide yes)
			(effects
				(font
					(size 1 1)
					(thickness 0.15)
				)
				(justify mirror)
			)
		)
		(property "Voltage" ""
			(at 415.3 260 0)
			(layer "B.Fab")
			(hide yes)
			(effects
				(font
					(size 1 1)
					(thickness 0.15)
				)
				(justify mirror)
			)
		)
		(sheetname "FPGA supply")
		(sheetfile "fpga-supply.kicad_sch")
		(attr smd)
		(fp_line
			(start -0.15 0.4)
			(end 0.15 0.4)
			(stroke
				(width 0.15)
				(type solid)
			)
			(layer "B.SilkS")
		)
		(fp_line
			(start -0.15 -0.4)
			(end 0.15 -0.4)
			(stroke
				(width 0.15)
				(type solid)
			)
			(layer "B.SilkS")
		)
		(fp_rect
			(start -1.25 0.65)
			(end 1.25 -0.65)
			(stroke
				(width 0.05)
				(type solid)
			)
			(fill no)
			(layer "B.CrtYd")
		)
		(fp_rect
			(start -0.8 0.4)
			(end 0.8 -0.4)
			(stroke
				(width 0.15)
				(type solid)
			)
			(fill no)
			(layer "B.Fab")
		)
		(pad "1" smd roundrect
			(at -0.7 0 180)
			(size 0.8 1)
			(layers "B.Cu" "B.Mask" "B.Paste")
			(roundrect_rratio 0.2)
			(net 1 "GND")
			(pintype "passive")
		)
		(pad "2" smd roundrect
			(at 0.7 0 180)
			(size 0.8 1)
			(layers "B.Cu" "B.Mask" "B.Paste")
			(roundrect_rratio 0.2)
			(net 650 "+1V0")
			(pintype "passive")
		)
	)
	(footprint "antmicro-footprints:R_0402_1005Metric"
		(layer "B.Cu")
		(at 198.991252 99.25 -90)
		(descr "Resistor SMD 0402")
		(tags "resistor SMD 0402")
		(property "Reference" "R206"
			(at 3.8 -0.433748 90)
			(layer "B.SilkS")
			(effects
				(font
					(size 0.7 0.7)
					(thickness 0.15)
				)
				(justify left bottom mirror)
			)
		)
		(property "Value" "R_10k_0402"
			(at 0 -1.4 90)
			(layer "B.Fab")
			(effects
				(font
					(size 0.7 0.7)
					(thickness 0.15)
				)
				(justify left bottom mirror)
			)
		)
		(property "Description" "SMD Chip Resistor, 10 kohm, ± 1%, 62.5 mW, 0402 [1005 Metric], Thick Film, General Purpose"
			(at 0 0 270)
			(layer "F.Fab")
			(hide yes)
			(effects
				(font
					(size 1.27 1.27)
					(thickness 0.15)
				)
			)
		)
		(property "Author" "Antmicro"
			(at 99.741252 298.241252 0)
			(layer "B.Fab")
			(hide yes)
			(effects
				(font
					(size 1 1)
					(thickness 0.15)
				)
				(justify mirror)
			)
		)
		(property "License" "Apache-2.0"
			(at 99.741252 298.241252 0)
			(layer "B.Fab")
			(hide yes)
			(effects
				(font
					(size 1 1)
					(thickness 0.15)
				)
				(justify mirror)
			)
		)
		(property "MPN" "CR0402-FX-1002GLF"
			(at 99.741252 298.241252 0)
			(layer "B.Fab")
			(hide yes)
			(effects
				(font
					(size 1 1)
					(thickness 0.15)
				)
				(justify mirror)
			)
		)
		(property "Manufacturer" "Bourns"
			(at 99.741252 298.241252 0)
			(layer "B.Fab")
			(hide yes)
			(effects
				(font
					(size 1 1)
					(thickness 0.15)
				)
				(justify mirror)
			)
		)
		(property "Tolerance" "1%"
			(at 99.741252 298.241252 0)
			(layer "B.Fab")
			(hide yes)
			(effects
				(font
					(size 1 1)
					(thickness 0.15)
				)
				(justify mirror)
			)
		)
		(property "Val" "10k"
			(at 99.741252 298.241252 0)
			(layer "B.Fab")
			(hide yes)
			(effects
				(font
					(size 1 1)
					(thickness 0.15)
				)
				(justify mirror)
			)
		)
		(sheetname "HDMI + Ethernet")
		(sheetfile "hdmi-ethernet.kicad_sch")
		(attr smd)
		(fp_rect
			(start -0.925 0.47)
			(end 0.925 -0.47)
			(stroke
				(width 0.05)
				(type default)
			)
			(fill no)
			(layer "B.CrtYd")
		)
		(fp_rect
			(start -0.5 0.25)
			(end 0.5 -0.25)
			(stroke
				(width 0.15)
				(type solid)
			)
			(fill no)
			(layer "B.Fab")
		)
		(pad "1" smd roundrect
			(at -0.48 0 270)
			(size 0.59 0.64)
			(layers "B.Cu" "B.Mask" "B.Paste")
			(roundrect_rratio 0.25)
			(net 508 "/FPGA Bank 16 & 17/GBE_RGMII.~{INT}")
			(pintype "passive")
		)
		(pad "2" smd roundrect
			(at 0.48 0 270)
			(size 0.59 0.64)
			(layers "B.Cu" "B.Mask" "B.Paste")
			(roundrect_rratio 0.25)
			(net 24 "+3V3")
			(pintype "passive")
		)
	)
	(footprint "antmicro-footprints:C_0402_1005Metric"
		(layer "B.Cu")
		(at 211 144.5 180)
		(descr "Capacitor SMD 0402")
		(tags "capacitor SMD 0402")
		(property "Reference" "C12"
			(at -1.15 0.45 0)
			(layer "B.SilkS")
			(effects
				(font
					(size 0.7 0.7)
					(thickness 0.15)
				)
				(justify left bottom mirror)
			)
		)
		(property "Value" "C_100n_0402"
			(at 0 -1.169 0)
			(layer "B.Fab")
			(effects
				(font
					(size 0.7 0.7)
					(thickness 0.15)
				)
				(justify left bottom mirror)
			)
		)
		(property "Description" "SMD Multilayer Ceramic Capacitor, 0.1 µF, 50 V, 0402 [1005 Metric], ± 10%, X5R, GRM Series"
			(at 0 0 180)
			(layer "F.Fab")
			(hide yes)
			(effects
				(font
					(size 1.27 1.27)
					(thickness 0.15)
				)
			)
		)
		(property "Author" "Antmicro"
			(at 422 289 0)
			(layer "B.Fab")
			(hide yes)
			(effects
				(font
					(size 1 1)
					(thickness 0.15)
				)
				(justify mirror)
			)
		)
		(property "Dielectric" "X5R"
			(at 422 289 0)
			(layer "B.Fab")
			(hide yes)
			(effects
				(font
					(size 1 1)
					(thickness 0.15)
				)
				(justify mirror)
			)
		)
		(property "License" "Apache-2.0"
			(at 422 289 0)
			(layer "B.Fab")
			(hide yes)
			(effects
				(font
					(size 1 1)
					(thickness 0.15)
				)
				(justify mirror)
			)
		)
		(property "MPN" "GRM155R61H104KE14D"
			(at 422 289 0)
			(layer "B.Fab")
			(hide yes)
			(effects
				(font
					(size 1 1)
					(thickness 0.15)
				)
				(justify mirror)
			)
		)
		(property "Manufacturer" "Murata"
			(at 422 289 0)
			(layer "B.Fab")
			(hide yes)
			(effects
				(font
					(size 1 1)
					(thickness 0.15)
				)
				(justify mirror)
			)
		)
		(property "Val" "100n"
			(at 422 289 0)
			(layer "B.Fab")
			(hide yes)
			(effects
				(font
					(size 1 1)
					(thickness 0.15)
				)
				(justify mirror)
			)
		)
		(property "Voltage" "50V"
			(at 422 289 0)
			(layer "B.Fab")
			(hide yes)
			(effects
				(font
					(size 1 1)
					(thickness 0.15)
				)
				(justify mirror)
			)
		)
		(sheetname "FPGA Bank 12 & 13")
		(sheetfile "fpga-bank-12-13.kicad_sch")
		(attr smd)
		(fp_rect
			(start -0.925 0.47)
			(end 0.925 -0.47)
			(stroke
				(width 0.05)
				(type default)
			)
			(fill no)
			(layer "B.CrtYd")
		)
		(fp_line
			(start 0.504 0.25)
			(end 0.504 -0.248)
			(stroke
				(width 0.15)
				(type solid)
			)
			(layer "B.Fab")
		)
		(fp_line
			(start 0.504 -0.248)
			(end -0.494 -0.248)
			(stroke
				(width 0.15)
				(type solid)
			)
			(layer "B.Fab")
		)
		(fp_line
			(start -0.494 0.25)
			(end 0.504 0.25)
			(stroke
				(width 0.15)
				(type solid)
			)
			(layer "B.Fab")
		)
		(fp_line
			(start -0.494 -0.248)
			(end -0.494 0.25)
			(stroke
				(width 0.15)
				(type solid)
			)
			(layer "B.Fab")
		)
		(pad "1" smd roundrect
			(at -0.48 0 180)
			(size 0.59 0.64)
			(layers "B.Cu" "B.Mask" "B.Paste")
			(roundrect_rratio 0.25)
			(net 1 "GND")
			(pintype "passive")
		)
		(pad "2" smd roundrect
			(at 0.48 0 180)
			(size 0.59 0.64)
			(layers "B.Cu" "B.Mask" "B.Paste")
			(roundrect_rratio 0.25)
			(net 24 "+3V3")
			(pintype "passive")
		)
	)
	(footprint "antmicro-footprints:R_0402_1005Metric"
		(layer "B.Cu")
		(at 198.491252 93.55)
		(descr "Resistor SMD 0402")
		(tags "resistor SMD 0402")
		(property "Reference" "R211"
			(at 1.483748 -4.6 180)
			(layer "B.SilkS")
			(effects
				(font
					(size 0.7 0.7)
					(thickness 0.15)
				)
				(justify left bottom mirror)
			)
		)
		(property "Value" "R_2k2_0402"
			(at 0 -1.4 180)
			(layer "B.Fab")
			(effects
				(font
					(size 0.7 0.7)
					(thickness 0.15)
				)
				(justify left bottom mirror)
			)
		)
		(property "Description" "SMD Chip Resistor, 2.2 kohm, ± 1%, 62.5 mW, 0402 [1005 Metric], Thick Film, General Purpose"
			(at 0 0 0)
			(layer "F.Fab")
			(hide yes)
			(effects
				(font
					(size 1.27 1.27)
					(thickness 0.15)
				)
			)
		)
		(property "Author" "Antmicro"
			(at 0 0 0)
			(layer "B.Fab")
			(hide yes)
			(effects
				(font
					(size 1 1)
					(thickness 0.15)
				)
				(justify mirror)
			)
		)
		(property "License" "Apache-2.0"
			(at 0 0 0)
			(layer "B.Fab")
			(hide yes)
			(effects
				(font
					(size 1 1)
					(thickness 0.15)
				)
				(justify mirror)
			)
		)
		(property "MPN" "CR0402-FX-2201GLF"
			(at 0 0 0)
			(layer "B.Fab")
			(hide yes)
			(effects
				(font
					(size 1 1)
					(thickness 0.15)
				)
				(justify mirror)
			)
		)
		(property "Manufacturer" "Bourns"
			(at 0 0 0)
			(layer "B.Fab")
			(hide yes)
			(effects
				(font
					(size 1 1)
					(thickness 0.15)
				)
				(justify mirror)
			)
		)
		(property "Tolerance" "1%"
			(at 0 0 0)
			(layer "B.Fab")
			(hide yes)
			(effects
				(font
					(size 1 1)
					(thickness 0.15)
				)
				(justify mirror)
			)
		)
		(property "Val" "2k2"
			(at 0 0 0)
			(layer "B.Fab")
			(hide yes)
			(effects
				(font
					(size 1 1)
					(thickness 0.15)
				)
				(justify mirror)
			)
		)
		(sheetname "HDMI + Ethernet")
		(sheetfile "hdmi-ethernet.kicad_sch")
		(attr smd)
		(fp_rect
			(start -0.925 0.47)
			(end 0.925 -0.47)
			(stroke
				(width 0.05)
				(type default)
			)
			(fill no)
			(layer "B.CrtYd")
		)
		(fp_rect
			(start -0.5 0.25)
			(end 0.5 -0.25)
			(stroke
				(width 0.15)
				(type solid)
			)
			(fill no)
			(layer "B.Fab")
		)
		(pad "1" smd roundrect
			(at -0.48 0)
			(size 0.59 0.64)
			(layers "B.Cu" "B.Mask" "B.Paste")
			(roundrect_rratio 0.25)
			(net 505 "/FPGA Bank 16 & 17/GBE_RGMII.RXD1")
			(pintype "passive")
		)
		(pad "2" smd roundrect
			(at 0.48 0)
			(size 0.59 0.64)
			(layers "B.Cu" "B.Mask" "B.Paste")
			(roundrect_rratio 0.25)
			(net 1 "GND")
			(pintype "passive")
		)
	)
)
